(kicad_pcb
	(version 20260206)
	(generator "pcbnew")
	(generator_version "10.0")
	(general
		(thickness 1.6)
		(legacy_teardrops no)
	)
	(paper "A4")
	(title_block
		(title "dpb — 14545-sa.0730WZS0815.brd")
		(comment 1 "Honey Badger (Wiwynn) / footprints 999-1006 of 1066")
	)
	(layers
		(0 "F.Cu" signal "TOP")
		(4 "In1.Cu" signal "L2GND")
		(6 "In2.Cu" signal "L3")
		(8 "In3.Cu" signal "L4VCC")
		(10 "In4.Cu" signal "L5VCC")
		(12 "In5.Cu" signal "L6")
		(14 "In6.Cu" signal "L7GND")
		(2 "B.Cu" signal "BOTTOM")
		(9 "F.Adhes" user "F.Adhesive")
		(11 "B.Adhes" user "B.Adhesive")
		(13 "F.Paste" user "Package Geometry/Pastemask Top")
		(15 "B.Paste" user "Package Geometry/Pastemask Bottom")
		(5 "F.SilkS" user "Ref Des/Silkscreen Top")
		(7 "B.SilkS" user "Ref Des/Silkscreen Bottom")
		(1 "F.Mask" user "Board Geometry/Soldermask Top")
		(3 "B.Mask" user "Board Geometry/Soldermask Bottom")
		(17 "Dwgs.User" user "User.Drawings")
		(19 "Cmts.User" user "User.Comments")
		(21 "Eco1.User" user "User.Eco1")
		(23 "Eco2.User" user "User.Eco2")
		(25 "Edge.Cuts" user "Board Geometry/Outline")
		(27 "Margin" user)
		(31 "F.CrtYd" user "Package Geometry/Place Bound Top")
		(29 "B.CrtYd" user "Package Geometry/Place Bound Bottom")
		(35 "F.Fab" user "Ref Des/Assembly Top")
		(33 "B.Fab" user "Ref Des/Assembly Bottom")
	)
	(footprint ""
		(layer "F.Cu")
		(at 27.876246 -374.9167 -90)
		(property "Reference" "R321"
			(at 0 0 270)
			(layer "F.SilkS")
			(hide yes)
			(effects
				(font
					(size 1.27 1.27)
				)
			)
		)
		(property "Value" "4K7R2J-2-GP"
			(at 0.064008 -3.993896 270)
			(unlocked yes)
			(layer "F.Fab")
			(hide yes)
			(effects
				(font
					(size 1.016 1.016)
					(thickness 0.1524)
				)
			)
		)
		(property "Device Type" "R402H16"
			(at 0.064008 -5.517896 270)
			(unlocked yes)
			(layer "F.Fab")
			(hide yes)
			(effects
				(font
					(size 1.016 1.016)
					(thickness 0.1524)
				)
			)
		)
		(duplicate_pad_numbers_are_jumpers no)
		(fp_line
			(start -0.508 -0.9398)
			(end -0.508 0.9398)
			(stroke
				(width 0.1524)
				(type default)
			)
			(layer "F.SilkS")
		)
		(fp_line
			(start 0.508 -0.9398)
			(end -0.508 -0.9398)
			(stroke
				(width 0.1524)
				(type default)
			)
			(layer "F.SilkS")
		)
		(fp_rect
			(start -0.508 0.9398)
			(end 0.508 -0.9398)
			(stroke
				(width 0)
				(type default)
			)
			(fill no)
			(layer "F.CrtYd")
		)
		(fp_rect
			(start -0.508 0.9398)
			(end 0.508 -0.9398)
			(stroke
				(width 0)
				(type default)
			)
			(fill no)
			(layer "F.Fab")
		)
		(pad "1" smd custom
			(at 0 -0.4445 270)
			(size 0.1397 0.1397)
			(layers "F.Cu" "F.Mask" "F.Paste")
			(net "I2C_B_TMP1_A1")
			(options
				(clearance outline)
				(anchor circle)
			)
			(primitives
				(gr_poly
					(pts
						(arc
							(start -0.1778 -0.2794)
							(mid -0.249642 -0.249642)
							(end -0.2794 -0.1778)
						)
						(arc
							(start -0.2794 0.1778)
							(mid -0.249642 0.249642)
							(end -0.1778 0.2794)
						)
						(arc
							(start 0.1778 0.2794)
							(mid 0.249642 0.249642)
							(end 0.2794 0.1778)
						)
						(arc
							(start 0.2794 -0.1778)
							(mid 0.249642 -0.249642)
							(end 0.1778 -0.2794)
						)
					)
					(width 0)
					(fill yes)
				)
			)
		)
		(pad "2" smd custom
			(at 0 0.4445 270)
			(size 0.1397 0.1397)
			(layers "F.Cu" "F.Mask" "F.Paste")
			(net "GND")
			(options
				(clearance outline)
				(anchor circle)
			)
			(primitives
				(gr_poly
					(pts
						(arc
							(start -0.1778 -0.2794)
							(mid -0.249642 -0.249642)
							(end -0.2794 -0.1778)
						)
						(arc
							(start -0.2794 0.1778)
							(mid -0.249642 0.249642)
							(end -0.1778 0.2794)
						)
						(arc
							(start 0.1778 0.2794)
							(mid 0.249642 0.249642)
							(end 0.2794 0.1778)
						)
						(arc
							(start 0.2794 -0.1778)
							(mid 0.249642 -0.249642)
							(end 0.1778 -0.2794)
						)
					)
					(width 0)
					(fill yes)
				)
			)
		)
	)
	(footprint ""
		(layer "F.Cu")
		(at 57.768236 -493.518698 90)
		(property "Reference" "R178"
			(at 0 0 90)
			(layer "F.SilkS")
			(hide yes)
			(effects
				(font
					(size 1.27 1.27)
				)
			)
		)
		(property "Value" "2R2010J-1-GP"
			(at 0.254 -8.0772 90)
			(unlocked yes)
			(layer "F.Fab")
			(hide yes)
			(effects
				(font
					(size 1.016 1.016)
					(thickness 0.1524)
				)
			)
		)
		(property "Device Type" "R2010H28"
			(at 0.254 -9.6774 90)
			(unlocked yes)
			(layer "F.Fab")
			(hide yes)
			(effects
				(font
					(size 1.016 1.016)
					(thickness 0.1524)
				)
			)
		)
		(duplicate_pad_numbers_are_jumpers no)
		(fp_line
			(start 1.651 -3.302)
			(end -1.651 -3.302)
			(stroke
				(width 0.1524)
				(type default)
			)
			(layer "F.SilkS")
		)
		(fp_line
			(start -1.651 -3.302)
			(end -1.651 3.302)
			(stroke
				(width 0.1524)
				(type default)
			)
			(layer "F.SilkS")
		)
		(fp_line
			(start 1.651 3.302)
			(end 1.651 -3.302)
			(stroke
				(width 0.1524)
				(type default)
			)
			(layer "F.SilkS")
		)
		(fp_line
			(start -1.651 3.302)
			(end 1.651 3.302)
			(stroke
				(width 0.1524)
				(type default)
			)
			(layer "F.SilkS")
		)
		(fp_rect
			(start -1.7272 -3.3782)
			(end 1.7272 3.3782)
			(stroke
				(width 0)
				(type default)
			)
			(fill no)
			(layer "F.CrtYd")
		)
		(fp_poly
			(pts
				(xy 1.7272 3.3782) (xy 1.7272 -3.3782) (xy -1.7272 -3.3782) (xy -1.7272 3.3782)
			)
			(stroke
				(width 0)
				(type default)
			)
			(fill no)
			(layer "F.Fab")
		)
		(pad "1" smd rect
			(at 0 -2.3495 90)
			(size 2.794 1.143)
			(layers "F.Cu" "F.Mask" "F.Paste")
			(net "12V_PRE_5")
		)
		(pad "2" smd rect
			(at 0 2.3495 90)
			(size 2.794 1.143)
			(layers "F.Cu" "F.Mask" "F.Paste")
			(net "P12V_HDD5")
		)
	)
	(footprint ""
		(layer "F.Cu")
		(at 209.295746 -40.9067 180)
		(property "Reference" "R332"
			(at 0 0 180)
			(layer "F.SilkS")
			(hide yes)
			(effects
				(font
					(size 1.27 1.27)
				)
			)
		)
		(property "Value" "4K7R2J-2-GP"
			(at 0.064008 -3.993896 180)
			(unlocked yes)
			(layer "F.Fab")
			(hide yes)
			(effects
				(font
					(size 1.016 1.016)
					(thickness 0.1524)
				)
			)
		)
		(property "Device Type" "R402H16"
			(at 0.064008 -5.517896 180)
			(unlocked yes)
			(layer "F.Fab")
			(hide yes)
			(effects
				(font
					(size 1.016 1.016)
					(thickness 0.1524)
				)
			)
		)
		(duplicate_pad_numbers_are_jumpers no)
		(fp_line
			(start 0.508 -0.9398)
			(end -0.508 -0.9398)
			(stroke
				(width 0.1524)
				(type default)
			)
			(layer "F.SilkS")
		)
		(fp_line
			(start -0.508 -0.9398)
			(end -0.508 0.9398)
			(stroke
				(width 0.1524)
				(type default)
			)
			(layer "F.SilkS")
		)
		(fp_rect
			(start -0.508 0.9398)
			(end 0.508 -0.9398)
			(stroke
				(width 0)
				(type default)
			)
			(fill no)
			(layer "F.CrtYd")
		)
		(fp_rect
			(start -0.508 0.9398)
			(end 0.508 -0.9398)
			(stroke
				(width 0)
				(type default)
			)
			(fill no)
			(layer "F.Fab")
		)
		(pad "1" smd custom
			(at 0 -0.4445 180)
			(size 0.1397 0.1397)
			(layers "F.Cu" "F.Mask" "F.Paste")
			(net "P3V3")
			(options
				(clearance outline)
				(anchor circle)
			)
			(primitives
				(gr_poly
					(pts
						(arc
							(start -0.1778 -0.2794)
							(mid -0.249642 -0.249642)
							(end -0.2794 -0.1778)
						)
						(arc
							(start -0.2794 0.1778)
							(mid -0.249642 0.249642)
							(end -0.1778 0.2794)
						)
						(arc
							(start 0.1778 0.2794)
							(mid 0.249642 0.249642)
							(end 0.2794 0.1778)
						)
						(arc
							(start 0.2794 -0.1778)
							(mid 0.249642 -0.249642)
							(end 0.1778 -0.2794)
						)
					)
					(width 0)
					(fill yes)
				)
			)
		)
		(pad "2" smd custom
			(at 0 0.4445 180)
			(size 0.1397 0.1397)
			(layers "F.Cu" "F.Mask" "F.Paste")
			(net "I2C_B_TMP4_A1")
			(options
				(clearance outline)
				(anchor circle)
			)
			(primitives
				(gr_poly
					(pts
						(arc
							(start -0.1778 -0.2794)
							(mid -0.249642 -0.249642)
							(end -0.2794 -0.1778)
						)
						(arc
							(start -0.2794 0.1778)
							(mid -0.249642 0.249642)
							(end -0.1778 0.2794)
						)
						(arc
							(start 0.1778 0.2794)
							(mid 0.249642 0.249642)
							(end 0.2794 0.1778)
						)
						(arc
							(start 0.2794 -0.1778)
							(mid 0.249642 -0.249642)
							(end 0.1778 -0.2794)
						)
					)
					(width 0)
					(fill yes)
				)
			)
		)
	)
	(footprint ""
		(layer "F.Cu")
		(at 60.375292 -87.912956 180)
		(property "Reference" "C256"
			(at 0 0 180)
			(layer "F.SilkS")
			(hide yes)
			(effects
				(font
					(size 1.27 1.27)
				)
			)
		)
		(property "Value" "SC10U25V6KX-1GP"
			(at -0.0762 -5.1308 180)
			(unlocked yes)
			(layer "F.Fab")
			(hide yes)
			(effects
				(font
					(size 1.016 1.016)
					(thickness 0.1524)
				)
			)
		)
		(property "Device Type" "C1206H71"
			(at -0.127 -6.6548 180)
			(unlocked yes)
			(layer "F.Fab")
			(hide yes)
			(effects
				(font
					(size 1.016 1.016)
					(thickness 0.1524)
				)
			)
		)
		(duplicate_pad_numbers_are_jumpers no)
		(fp_line
			(start 1.016 2.2352)
			(end -1.016 2.2352)
			(stroke
				(width 0.1524)
				(type default)
			)
			(layer "F.SilkS")
		)
		(fp_line
			(start 1.016 0.8382)
			(end 1.016 2.2352)
			(stroke
				(width 0.1524)
				(type default)
			)
			(layer "F.SilkS")
		)
		(fp_line
			(start 1.016 -2.2352)
			(end 1.016 -0.8382)
			(stroke
				(width 0.1524)
				(type default)
			)
			(layer "F.SilkS")
		)
		(fp_line
			(start -1.016 2.2352)
			(end -1.016 0.8382)
			(stroke
				(width 0.1524)
				(type default)
			)
			(layer "F.SilkS")
		)
		(fp_line
			(start -1.016 -0.8382)
			(end -1.016 -2.2352)
			(stroke
				(width 0.1524)
				(type default)
			)
			(layer "F.SilkS")
		)
		(fp_line
			(start -1.016 -2.2352)
			(end 1.016 -2.2352)
			(stroke
				(width 0.1524)
				(type default)
			)
			(layer "F.SilkS")
		)
		(fp_rect
			(start -1.0922 2.3114)
			(end 1.0922 -2.3114)
			(stroke
				(width 0)
				(type default)
			)
			(fill no)
			(layer "F.CrtYd")
		)
		(fp_poly
			(pts
				(xy 1.0922 -2.3114) (xy 1.0922 2.3114) (xy -1.0922 2.3114) (xy -1.0922 -2.3114)
			)
			(stroke
				(width 0)
				(type default)
			)
			(fill no)
			(layer "F.Fab")
		)
		(pad "1" smd rect
			(at 0 -1.397 180)
			(size 1.651 1.27)
			(layers "F.Cu" "F.Mask" "F.Paste")
			(net "P12V_HDD9")
		)
		(pad "2" smd rect
			(at 0 1.397 180)
			(size 1.651 1.27)
			(layers "F.Cu" "F.Mask" "F.Paste")
			(net "GND")
		)
	)
	(footprint ""
		(layer "F.Cu")
		(at 78.5622 -500.907304 180)
		(property "Reference" "C384"
			(at 0 0 180)
			(layer "F.SilkS")
			(hide yes)
			(effects
				(font
					(size 1.27 1.27)
				)
			)
		)
		(property "Value" "SCD033U25V2KX-GP"
			(at 1.1811 -2.7051 180)
			(unlocked yes)
			(layer "F.Fab")
			(hide yes)
			(effects
				(font
					(size 1.016 1.016)
					(thickness 0.1524)
				)
			)
		)
		(property "Device Type" "C402H22"
			(at 1.1811 -4.2291 180)
			(unlocked yes)
			(layer "F.Fab")
			(hide yes)
			(effects
				(font
					(size 1.016 1.016)
					(thickness 0.1524)
				)
			)
		)
		(duplicate_pad_numbers_are_jumpers no)
		(fp_rect
			(start -0.4318 0.9525)
			(end 0.4318 -0.9525)
			(stroke
				(width 0)
				(type default)
			)
			(fill no)
			(layer "F.CrtYd")
		)
		(fp_rect
			(start -0.4318 0.9525)
			(end 0.4318 -0.9525)
			(stroke
				(width 0)
				(type default)
			)
			(fill no)
			(layer "F.Fab")
		)
		(pad "1" smd custom
			(at 0 -0.4445 180)
			(size 0.1524 0.1524)
			(layers "F.Cu" "F.Mask" "F.Paste")
			(net "P12V")
			(options
				(clearance outline)
				(anchor circle)
			)
			(primitives
				(gr_poly
					(pts
						(arc
							(start 0.3048 -0.2032)
							(mid 0.275042 -0.275042)
							(end 0.2032 -0.3048)
						)
						(arc
							(start -0.2032 -0.3048)
							(mid -0.275042 -0.275042)
							(end -0.3048 -0.2032)
						)
						(arc
							(start -0.3048 0.2032)
							(mid -0.275042 0.275042)
							(end -0.2032 0.3048)
						)
						(arc
							(start 0.2032 0.3048)
							(mid 0.275042 0.275042)
							(end 0.3048 0.2032)
						)
					)
					(width 0)
					(fill yes)
				)
			)
		)
		(pad "2" smd custom
			(at 0 0.4445 180)
			(size 0.1524 0.1524)
			(layers "F.Cu" "F.Mask" "F.Paste")
			(net "SW_HDD5_N")
			(options
				(clearance outline)
				(anchor circle)
			)
			(primitives
				(gr_poly
					(pts
						(arc
							(start 0.3048 -0.2032)
							(mid 0.275042 -0.275042)
							(end 0.2032 -0.3048)
						)
						(arc
							(start -0.2032 -0.3048)
							(mid -0.275042 -0.275042)
							(end -0.3048 -0.2032)
						)
						(arc
							(start -0.3048 0.2032)
							(mid -0.275042 0.275042)
							(end -0.2032 0.3048)
						)
						(arc
							(start 0.2032 0.3048)
							(mid 0.275042 0.275042)
							(end 0.3048 0.2032)
						)
					)
					(width 0)
					(fill yes)
				)
			)
		)
	)
	(footprint ""
		(layer "F.Cu")
		(at 79.191358 -499.412514 90)
		(property "Reference" "R180"
			(at 0 0 90)
			(layer "F.SilkS")
			(hide yes)
			(effects
				(font
					(size 1.27 1.27)
				)
			)
		)
		(property "Value" "4K7R2J-2-GP"
			(at 0.064008 -3.993896 90)
			(unlocked yes)
			(layer "F.Fab")
			(hide yes)
			(effects
				(font
					(size 1.016 1.016)
					(thickness 0.1524)
				)
			)
		)
		(property "Device Type" "R402H16"
			(at 0.064008 -5.517896 90)
			(unlocked yes)
			(layer "F.Fab")
			(hide yes)
			(effects
				(font
					(size 1.016 1.016)
					(thickness 0.1524)
				)
			)
		)
		(duplicate_pad_numbers_are_jumpers no)
		(fp_line
			(start 0.508 -0.9398)
			(end -0.508 -0.9398)
			(stroke
				(width 0.1524)
				(type default)
			)
			(layer "F.SilkS")
		)
		(fp_line
			(start -0.508 -0.9398)
			(end -0.508 0.9398)
			(stroke
				(width 0.1524)
				(type default)
			)
			(layer "F.SilkS")
		)
		(fp_rect
			(start -0.508 0.9398)
			(end 0.508 -0.9398)
			(stroke
				(width 0)
				(type default)
			)
			(fill no)
			(layer "F.CrtYd")
		)
		(fp_rect
			(start -0.508 0.9398)
			(end 0.508 -0.9398)
			(stroke
				(width 0)
				(type default)
			)
			(fill no)
			(layer "F.Fab")
		)
		(pad "1" smd custom
			(at 0 -0.4445 90)
			(size 0.1397 0.1397)
			(layers "F.Cu" "F.Mask" "F.Paste")
			(net "P12V")
			(options
				(clearance outline)
				(anchor circle)
			)
			(primitives
				(gr_poly
					(pts
						(arc
							(start -0.1778 -0.2794)
							(mid -0.249642 -0.249642)
							(end -0.2794 -0.1778)
						)
						(arc
							(start -0.2794 0.1778)
							(mid -0.249642 0.249642)
							(end -0.1778 0.2794)
						)
						(arc
							(start 0.1778 0.2794)
							(mid 0.249642 0.249642)
							(end 0.2794 0.1778)
						)
						(arc
							(start 0.2794 -0.1778)
							(mid 0.249642 -0.249642)
							(end 0.1778 -0.2794)
						)
					)
					(width 0)
					(fill yes)
				)
			)
		)
		(pad "2" smd custom
			(at 0 0.4445 90)
			(size 0.1397 0.1397)
			(layers "F.Cu" "F.Mask" "F.Paste")
			(net "SW_HDD5_R")
			(options
				(clearance outline)
				(anchor circle)
			)
			(primitives
				(gr_poly
					(pts
						(arc
							(start -0.1778 -0.2794)
							(mid -0.249642 -0.249642)
							(end -0.2794 -0.1778)
						)
						(arc
							(start -0.2794 0.1778)
							(mid -0.249642 0.249642)
							(end -0.1778 0.2794)
						)
						(arc
							(start 0.1778 0.2794)
							(mid 0.249642 0.249642)
							(end 0.2794 0.1778)
						)
						(arc
							(start 0.2794 -0.1778)
							(mid 0.249642 -0.249642)
							(end 0.1778 -0.2794)
						)
					)
					(width 0)
					(fill yes)
				)
			)
		)
	)
	(footprint ""
		(layer "F.Cu")
		(at 61.976 -174.2948)
		(property "Reference" "Q62"
			(at 0 0 0)
			(layer "F.SilkS")
			(hide yes)
			(effects
				(font
					(size 1.27 1.27)
				)
			)
		)
		(property "Value" "2N7002DW-7F-GP"
			(at -2.3622 -8.2042 0)
			(unlocked yes)
			(layer "F.Fab")
			(hide yes)
			(effects
				(font
					(size 1.016 1.016)
					(thickness 0.1524)
				)
			)
		)
		(property "Device Type" "SOT-363H44"
			(at -2.3622 -10.1092 0)
			(unlocked yes)
			(layer "F.Fab")
			(hide yes)
			(effects
				(font
					(size 1.016 1.016)
					(thickness 0.1524)
				)
			)
		)
		(duplicate_pad_numbers_are_jumpers no)
		(fp_line
			(start -1.4478 -1.7018)
			(end -1.4478 1.7018)
			(stroke
				(width 0.1524)
				(type default)
			)
			(layer "F.SilkS")
		)
		(fp_line
			(start -1.4478 1.7018)
			(end 1.4478 1.7018)
			(stroke
				(width 0.1524)
				(type default)
			)
			(layer "F.SilkS")
		)
		(fp_line
			(start -1.27 1.524)
			(end -1.27 0.6604)
			(stroke
				(width 0.4826)
				(type default)
			)
			(layer "F.SilkS")
		)
		(fp_line
			(start 1.4478 -1.7018)
			(end -1.4478 -1.7018)
			(stroke
				(width 0.1524)
				(type default)
			)
			(layer "F.SilkS")
		)
		(fp_line
			(start 1.4478 1.7018)
			(end 1.4478 -1.7018)
			(stroke
				(width 0.1524)
				(type default)
			)
			(layer "F.SilkS")
		)
		(fp_poly
			(pts
				(xy -1.524 -1.778) (xy 1.524 -1.778) (xy 1.524 1.778) (xy -1.524 1.778)
			)
			(stroke
				(width 0)
				(type default)
			)
			(fill no)
			(layer "F.CrtYd")
		)
		(fp_poly
			(pts
				(xy -1.524 -1.778) (xy 1.524 -1.778) (xy 1.524 1.778) (xy -1.524 1.778)
			)
			(stroke
				(width 0)
				(type default)
			)
			(fill no)
			(layer "F.Fab")
		)
		(pad "1" smd rect
			(at -0.65024 0.9398)
			(size 0.4064 1.016)
			(layers "F.Cu" "F.Mask" "F.Paste")
			(net "P3V3_HDD8_LED")
		)
		(pad "2" smd rect
			(at 0 0.9398)
			(size 0.4064 1.016)
			(layers "F.Cu" "F.Mask" "F.Paste")
			(net "HDD8_LED_G")
		)
		(pad "3" smd rect
			(at 0.65024 0.9398)
			(size 0.4064 1.016)
			(layers "F.Cu" "F.Mask" "F.Paste")
			(net "P5VB")
		)
		(pad "4" smd rect
			(at 0.65024 -0.9398)
			(size 0.4064 1.016)
			(layers "F.Cu" "F.Mask" "F.Paste")
			(net "P5VB_HDD8_LED")
		)
		(pad "5" smd rect
			(at 0 -0.9398)
			(size 0.4064 1.016)
			(layers "F.Cu" "F.Mask" "F.Paste")
			(net "HDD8_LED_G")
		)
		(pad "6" smd rect
			(at -0.65024 -0.9398)
			(size 0.4064 1.016)
			(layers "F.Cu" "F.Mask" "F.Paste")
			(net "P3V3")
		)
	)
	(footprint ""
		(layer "F.Cu")
		(at 218.646756 -469.039702 -90)
		(property "Reference" "C100"
			(at 0 0 270)
			(layer "F.SilkS")
			(hide yes)
			(effects
				(font
					(size 1.27 1.27)
				)
			)
		)
		(property "Value" "SCD01U50V2KX-1GP"
			(at 1.1811 -2.7051 270)
			(unlocked yes)
			(layer "F.Fab")
			(hide yes)
			(effects
				(font
					(size 1.016 1.016)
					(thickness 0.1524)
				)
			)
		)
		(property "Device Type" "C402H22"
			(at 1.1811 -4.2291 270)
			(unlocked yes)
			(layer "F.Fab")
			(hide yes)
			(effects
				(font
					(size 1.016 1.016)
					(thickness 0.1524)
				)
			)
		)
		(duplicate_pad_numbers_are_jumpers no)
		(fp_rect
			(start -0.4318 0.9525)
			(end 0.4318 -0.9525)
			(stroke
				(width 0)
				(type default)
			)
			(fill no)
			(layer "F.CrtYd")
		)
		(fp_rect
			(start -0.4318 0.9525)
			(end 0.4318 -0.9525)
			(stroke
				(width 0)
				(type default)
			)
			(fill no)
			(layer "F.Fab")
		)
		(pad "1" smd custom
			(at 0 -0.4445 270)
			(size 0.1524 0.1524)
			(layers "F.Cu" "F.Mask" "F.Paste")
			(net "SAS2X28_DRIVE_RX_N_A0")
			(options
				(clearance outline)
				(anchor circle)
			)
			(primitives
				(gr_poly
					(pts
						(arc
							(start 0.3048 -0.2032)
							(mid 0.275042 -0.275042)
							(end 0.2032 -0.3048)
						)
						(arc
							(start -0.2032 -0.3048)
							(mid -0.275042 -0.275042)
							(end -0.3048 -0.2032)
						)
						(arc
							(start -0.3048 0.2032)
							(mid -0.275042 0.275042)
							(end -0.2032 0.3048)
						)
						(arc
							(start 0.2032 0.3048)
							(mid 0.275042 0.275042)
							(end 0.3048 0.2032)
						)
					)
					(width 0)
					(fill yes)
				)
			)
		)
		(pad "2" smd custom
			(at 0 0.4445 270)
			(size 0.1524 0.1524)
			(layers "F.Cu" "F.Mask" "F.Paste")
			(net "SAS2X28_A_HDD0_RX_-")
			(options
				(clearance outline)
				(anchor circle)
			)
			(primitives
				(gr_poly
					(pts
						(arc
							(start 0.3048 -0.2032)
							(mid 0.275042 -0.275042)
							(end 0.2032 -0.3048)
						)
						(arc
							(start -0.2032 -0.3048)
							(mid -0.275042 -0.275042)
							(end -0.3048 -0.2032)
						)
						(arc
							(start -0.3048 0.2032)
							(mid -0.275042 0.275042)
							(end -0.2032 0.3048)
						)
						(arc
							(start 0.2032 0.3048)
							(mid 0.275042 0.275042)
							(end 0.3048 0.2032)
						)
					)
					(width 0)
					(fill yes)
				)
			)
		)
	)
)
